# BASEBOARD_FAB2 (Tioga Pass) — schematic netlist excerpt (pin names and nets, part order shuffled) for the footprints in the layout excerpt that follows; sources: Cadence DE-HDL packaged netlist, KiCad conversion of Wiwynn_Tioga_Pass_MB.brd

C8E3  CAP_A  0.1UF 16V 10% X7R  pkg 0402V  page 196 : A = PWRGD_P12V_HSC ; B = GND

(kicad_pcb
	(version 20260206)
	(generator "pcbnew")
	(generator_version "10.0")
	(general
		(thickness 1.6)
		(legacy_teardrops no)
	)
	(paper "A4")
	(title_block
		(title "Wiwynn_Tioga_Pass_MB.brd")
		(comment 1 "Tioga Pass / footprints 1894-1894 of 4770")
	)
	(layers
		(0 "F.Cu" signal "TOP")
		(4 "In1.Cu" signal "L2GND")
		(6 "In2.Cu" signal "L3")
		(8 "In3.Cu" signal "L4GND")
		(10 "In4.Cu" signal "L5")
		(12 "In5.Cu" signal "L6GND")
		(14 "In6.Cu" signal "L7VCC")
		(16 "In7.Cu" signal "L8VCC")
		(18 "In8.Cu" signal "L9GND")
		(20 "In9.Cu" signal "L10")
		(22 "In10.Cu" signal "L11GND")
		(24 "In11.Cu" signal "L12")
		(26 "In12.Cu" signal "L13GND")
		(2 "B.Cu" signal "BOTTOM")
		(9 "F.Adhes" user "F.Adhesive")
		(11 "B.Adhes" user "B.Adhesive")
		(13 "F.Paste" user "Package Geometry/Pastemask Top")
		(15 "B.Paste" user "Package Geometry/Pastemask Bottom")
		(5 "F.SilkS" user "Ref Des/Silkscreen Top")
		(7 "B.SilkS" user "Ref Des/Silkscreen Bottom")
		(1 "F.Mask" user "Board Geometry/Soldermask Top")
		(3 "B.Mask" user "Board Geometry/Soldermask Bottom")
		(17 "Dwgs.User" user "User.Drawings")
		(19 "Cmts.User" user "User.Comments")
		(21 "Eco1.User" user "User.Eco1")
		(23 "Eco2.User" user "User.Eco2")
		(25 "Edge.Cuts" user "Board Geometry/Outline")
		(27 "Margin" user)
		(31 "F.CrtYd" user "Package Geometry/Place Bound Top")
		(29 "B.CrtYd" user "Package Geometry/Place Bound Bottom")
		(35 "F.Fab" user "Ref Des/Assembly Top")
		(33 "B.Fab" user "Ref Des/Assembly Bottom")
	)
	(footprint ""
		(layer "F.Cu")
		(at 400.685 -76.073)
		(property "Reference" "C8E3"
			(at 0 0 0)
			(layer "F.SilkS")
			(hide yes)
			(effects
				(font
					(size 1.27 1.27)
				)
			)
		)
		(property "Value" ""
			(at 0 0 0)
			(layer "F.Fab")
			(effects
				(font
					(size 1.27 1.27)
				)
			)
		)
		(duplicate_pad_numbers_are_jumpers no)
		(fp_poly
			(pts
				(xy 0.3048 -0.1016) (xy 0.3048 0.9906) (xy -0.3048 0.9906) (xy -0.3048 -0.1016)
			)
			(stroke
				(width 0)
				(type default)
			)
			(fill no)
			(layer "F.CrtYd")
		)
		(fp_line
			(start -0.3048 -0.1016)
			(end -0.3048 0.9906)
			(stroke
				(width 0.1)
				(type default)
			)
			(layer "F.Fab")
		)
		(fp_line
			(start -0.3048 0.9906)
			(end 0.3048 0.9906)
			(stroke
				(width 0.1)
				(type default)
			)
			(layer "F.Fab")
		)
		(fp_line
			(start 0.3048 -0.1016)
			(end -0.3048 -0.1016)
			(stroke
				(width 0.1)
				(type default)
			)
			(layer "F.Fab")
		)
		(fp_line
			(start 0.3048 0.9906)
			(end 0.3048 -0.1016)
			(stroke
				(width 0.1)
				(type default)
			)
			(layer "F.Fab")
		)
		(pad "1" smd rect
			(at 0 0)
			(size 0.508 0.508)
			(layers "F.Cu" "F.Mask" "F.Paste")
			(net "PWRGD_P12V_HSC")
		)
		(pad "2" smd rect
			(at 0 0.889)
			(size 0.508 0.508)
			(layers "F.Cu" "F.Mask" "F.Paste")
			(net "GND")
		)
		(zone
			(layer "F.Cu")
			(hatch none 0.5)
			(connect_pads
				(clearance 0)
			)
			(min_thickness 0.25)
			(keepout
				(tracks allowed)
				(vias not_allowed)
				(pads allowed)
				(copperpour not_allowed)
				(footprints allowed)
			)
			(placement
				(enabled no)
				(sheetname "")
			)
			(fill
				(thermal_gap 0.5)
				(thermal_bridge_width 0.5)
				(island_removal_mode 0)
			)
			(polygon
				(pts
					(xy 400.431 -75.819) (xy 400.939 -75.819) (xy 400.939 -75.438) (xy 400.431 -75.438)
				)
			)
		)
		(zone
			(layer "F.Cu")
			(hatch none 0.5)
			(connect_pads
				(clearance 0)
			)
			(min_thickness 0.25)
			(keepout
				(tracks not_allowed)
				(vias allowed)
				(pads allowed)
				(copperpour not_allowed)
				(footprints allowed)
			)
			(placement
				(enabled no)
				(sheetname "")
			)
			(fill
				(thermal_gap 0.5)
				(thermal_bridge_width 0.5)
				(island_removal_mode 0)
			)
			(polygon
				(pts
					(xy 400.431 -75.438) (xy 400.939 -75.438) (xy 400.939 -75.819) (xy 400.431 -75.819)
				)
			)
		)
	)
)
